# S9S_MB_2U (Grand Teton) — schematic netlist excerpt (pin names and nets, part order shuffled) for the footprints in the layout excerpt that follows; sources: Cadence DE-HDL packaged netlist, KiCad conversion of 03242023_DA0F0TMBIJ0_F0T_Motherboard_J_brd_V01_OCP.brd

R1546  Q_RES  2K 1% CHIP  pkg 0402LF  page 183 : A = SMB_SML0B_3V3AUX_SDA ; B = P3V3_AUX
C293  Q_CAP  22UF 4V 20% X6S  pkg C0402  page 77 : A = PVCCIN_CPU1 ; B = GND

(kicad_pcb
	(version 20260206)
	(generator "pcbnew")
	(generator_version "10.0")
	(general
		(thickness 1.6)
		(legacy_teardrops no)
	)
	(paper "A4")
	(title_block
		(title "03242023_DA0F0TMBIJ0_F0T_Motherboard_J_brd_V01_OCP.brd")
		(comment 1 "Grand Teton / footprints 206-207 of 6105")
	)
	(layers
		(0 "F.Cu" signal "TOP")
		(4 "In1.Cu" signal "GND")
		(6 "In2.Cu" signal "IN1")
		(8 "In3.Cu" signal "GND1")
		(10 "In4.Cu" signal "IN2")
		(12 "In5.Cu" signal "GND2")
		(14 "In6.Cu" signal "IN3")
		(16 "In7.Cu" signal "GND3")
		(18 "In8.Cu" signal "VCC")
		(20 "In9.Cu" signal "VCC1")
		(22 "In10.Cu" signal "GND4")
		(24 "In11.Cu" signal "IN4")
		(26 "In12.Cu" signal "GND5")
		(28 "In13.Cu" signal "IN5")
		(30 "In14.Cu" signal "GND6")
		(32 "In15.Cu" signal "IN6")
		(34 "In16.Cu" signal "GND7")
		(2 "B.Cu" signal "BOTTOM")
		(9 "F.Adhes" user "F.Adhesive")
		(11 "B.Adhes" user "B.Adhesive")
		(13 "F.Paste" user "Package Geometry/Pastemask Top")
		(15 "B.Paste" user "Package Geometry/Pastemask Bottom")
		(5 "F.SilkS" user "Ref Des/Silkscreen Top")
		(7 "B.SilkS" user "Ref Des/Silkscreen Bottom")
		(1 "F.Mask" user "Board Geometry/Soldermask Top")
		(3 "B.Mask" user "Board Geometry/Soldermask Bottom")
		(17 "Dwgs.User" user "User.Drawings")
		(19 "Cmts.User" user "User.Comments")
		(21 "Eco1.User" user "User.Eco1")
		(23 "Eco2.User" user "User.Eco2")
		(25 "Edge.Cuts" user "Board Geometry/Outline")
		(27 "Margin" user)
		(31 "F.CrtYd" user "Package Geometry/Place Bound Top")
		(29 "B.CrtYd" user "Package Geometry/Place Bound Bottom")
		(35 "F.Fab" user "Ref Des/Assembly Top")
		(33 "B.Fab" user "Ref Des/Assembly Bottom")
	)
	(footprint ""
		(layer "F.Cu")
		(at 309.522622 -35.804348)
		(property "Reference" "R1546"
			(at 0 0 0)
			(layer "F.SilkS")
			(hide yes)
			(effects
				(font
					(size 1.27 1.27)
				)
			)
		)
		(property "Value" ""
			(at 0 0 0)
			(layer "F.Fab")
			(effects
				(font
					(size 1.27 1.27)
				)
			)
		)
		(duplicate_pad_numbers_are_jumpers no)
		(fp_line
			(start -0.7874 -0.4064)
			(end 0.7874 -0.4064)
			(stroke
				(width 0.1524)
				(type default)
			)
			(layer "F.SilkS")
		)
		(fp_line
			(start -0.7874 0.4064)
			(end -0.7874 -0.4064)
			(stroke
				(width 0.1524)
				(type default)
			)
			(layer "F.SilkS")
		)
		(fp_line
			(start 0.7874 -0.4064)
			(end 0.7874 0.4064)
			(stroke
				(width 0.1524)
				(type default)
			)
			(layer "F.SilkS")
		)
		(fp_line
			(start 0.7874 0.4064)
			(end -0.7874 0.4064)
			(stroke
				(width 0.1524)
				(type default)
			)
			(layer "F.SilkS")
		)
		(fp_line
			(start -0.67945 -0.305054)
			(end -0.12065 -0.305054)
			(stroke
				(width 0.1)
				(type default)
			)
			(layer "F.Fab")
		)
		(fp_line
			(start -0.67945 0.3048)
			(end -0.67945 -0.305054)
			(stroke
				(width 0.1)
				(type default)
			)
			(layer "F.Fab")
		)
		(fp_line
			(start -0.12065 -0.305054)
			(end -0.12065 -0.2794)
			(stroke
				(width 0.1)
				(type default)
			)
			(layer "F.Fab")
		)
		(fp_line
			(start -0.12065 -0.2794)
			(end 0.12065 -0.2794)
			(stroke
				(width 0.1)
				(type default)
			)
			(layer "F.Fab")
		)
		(fp_line
			(start -0.12065 0.2794)
			(end -0.12065 0.3048)
			(stroke
				(width 0.1)
				(type default)
			)
			(layer "F.Fab")
		)
		(fp_line
			(start -0.12065 0.3048)
			(end -0.67945 0.3048)
			(stroke
				(width 0.1)
				(type default)
			)
			(layer "F.Fab")
		)
		(fp_line
			(start 0.120396 0.2794)
			(end -0.12065 0.2794)
			(stroke
				(width 0.1)
				(type default)
			)
			(layer "F.Fab")
		)
		(fp_line
			(start 0.120396 0.3048)
			(end 0.120396 0.2794)
			(stroke
				(width 0.1)
				(type default)
			)
			(layer "F.Fab")
		)
		(fp_line
			(start 0.12065 -0.3048)
			(end 0.67945 -0.3048)
			(stroke
				(width 0.1)
				(type default)
			)
			(layer "F.Fab")
		)
		(fp_line
			(start 0.12065 -0.2794)
			(end 0.12065 -0.3048)
			(stroke
				(width 0.1)
				(type default)
			)
			(layer "F.Fab")
		)
		(fp_line
			(start 0.67945 -0.3048)
			(end 0.67945 0.3048)
			(stroke
				(width 0.1)
				(type default)
			)
			(layer "F.Fab")
		)
		(fp_line
			(start 0.67945 0.3048)
			(end 0.120396 0.3048)
			(stroke
				(width 0.1)
				(type default)
			)
			(layer "F.Fab")
		)
		(pad "1" smd circle
			(at -0.40005 0)
			(size 0 0)
			(layers "F.Cu" "F.Mask" "F.Paste")
			(net "SMB_SML0B_3V3AUX_SDA")
		)
		(pad "2" smd circle
			(at 0.40005 0)
			(size 0 0)
			(layers "F.Cu" "F.Mask" "F.Paste")
			(net "P3V3_AUX")
		)
	)
	(footprint ""
		(layer "F.Cu")
		(at 116.561616 -251.375672 90)
		(property "Reference" "C293"
			(at 0 0 90)
			(layer "F.SilkS")
			(hide yes)
			(effects
				(font
					(size 1.27 1.27)
				)
			)
		)
		(property "Value" ""
			(at 0 0 90)
			(layer "F.Fab")
			(effects
				(font
					(size 1.27 1.27)
				)
			)
		)
		(duplicate_pad_numbers_are_jumpers no)
		(fp_line
			(start 0.7874 -0.4064)
			(end 0.7874 0.4064)
			(stroke
				(width 0.1524)
				(type default)
			)
			(layer "F.SilkS")
		)
		(fp_line
			(start -0.7874 -0.4064)
			(end 0.7874 -0.4064)
			(stroke
				(width 0.1524)
				(type default)
			)
			(layer "F.SilkS")
		)
		(fp_line
			(start 0.7874 0.4064)
			(end -0.7874 0.4064)
			(stroke
				(width 0.1524)
				(type default)
			)
			(layer "F.SilkS")
		)
		(fp_line
			(start -0.7874 0.4064)
			(end -0.7874 -0.4064)
			(stroke
				(width 0.1524)
				(type default)
			)
			(layer "F.SilkS")
		)
		(fp_line
			(start -0.12065 -0.305054)
			(end -0.12065 -0.2794)
			(stroke
				(width 0.1)
				(type default)
			)
			(layer "F.Fab")
		)
		(fp_line
			(start -0.67945 -0.305054)
			(end -0.12065 -0.305054)
			(stroke
				(width 0.1)
				(type default)
			)
			(layer "F.Fab")
		)
		(fp_line
			(start 0.67945 -0.3048)
			(end 0.67945 0.3048)
			(stroke
				(width 0.1)
				(type default)
			)
			(layer "F.Fab")
		)
		(fp_line
			(start 0.12065 -0.3048)
			(end 0.67945 -0.3048)
			(stroke
				(width 0.1)
				(type default)
			)
			(layer "F.Fab")
		)
		(fp_line
			(start 0.12065 -0.2794)
			(end 0.12065 -0.3048)
			(stroke
				(width 0.1)
				(type default)
			)
			(layer "F.Fab")
		)
		(fp_line
			(start -0.12065 -0.2794)
			(end 0.12065 -0.2794)
			(stroke
				(width 0.1)
				(type default)
			)
			(layer "F.Fab")
		)
		(fp_line
			(start 0.120396 0.2794)
			(end -0.12065 0.2794)
			(stroke
				(width 0.1)
				(type default)
			)
			(layer "F.Fab")
		)
		(fp_line
			(start -0.12065 0.2794)
			(end -0.12065 0.3048)
			(stroke
				(width 0.1)
				(type default)
			)
			(layer "F.Fab")
		)
		(fp_line
			(start 0.67945 0.3048)
			(end 0.120396 0.3048)
			(stroke
				(width 0.1)
				(type default)
			)
			(layer "F.Fab")
		)
		(fp_line
			(start 0.120396 0.3048)
			(end 0.120396 0.2794)
			(stroke
				(width 0.1)
				(type default)
			)
			(layer "F.Fab")
		)
		(fp_line
			(start -0.12065 0.3048)
			(end -0.67945 0.3048)
			(stroke
				(width 0.1)
				(type default)
			)
			(layer "F.Fab")
		)
		(fp_line
			(start -0.67945 0.3048)
			(end -0.67945 -0.305054)
			(stroke
				(width 0.1)
				(type default)
			)
			(layer "F.Fab")
		)
		(pad "1" smd circle
			(at -0.40005 0 90)
			(size 0 0)
			(layers "F.Cu" "F.Mask" "F.Paste")
			(net "PVCCIN_CPU1")
		)
		(pad "2" smd circle
			(at 0.40005 0 90)
			(size 0 0)
			(layers "F.Cu" "F.Mask" "F.Paste")
			(net "GND")
		)
	)
)
